(kicad_pcb
	(version 20260206)
	(generator "pcbnew")
	(generator_version "10.0")
	(general
		(thickness 1.6)
		(legacy_teardrops no)
	)
	(paper "A4")
	(title_block
		(title "03242023_DA0F0TMBIJ0_F0T_Motherboard_J_brd_V01_OCP.brd")
		(comment 1 "Grand Teton / footprints 4845-4851 of 6105")
	)
	(layers
		(0 "F.Cu" signal "TOP")
		(4 "In1.Cu" signal "GND")
		(6 "In2.Cu" signal "IN1")
		(8 "In3.Cu" signal "GND1")
		(10 "In4.Cu" signal "IN2")
		(12 "In5.Cu" signal "GND2")
		(14 "In6.Cu" signal "IN3")
		(16 "In7.Cu" signal "GND3")
		(18 "In8.Cu" signal "VCC")
		(20 "In9.Cu" signal "VCC1")
		(22 "In10.Cu" signal "GND4")
		(24 "In11.Cu" signal "IN4")
		(26 "In12.Cu" signal "GND5")
		(28 "In13.Cu" signal "IN5")
		(30 "In14.Cu" signal "GND6")
		(32 "In15.Cu" signal "IN6")
		(34 "In16.Cu" signal "GND7")
		(2 "B.Cu" signal "BOTTOM")
		(9 "F.Adhes" user "F.Adhesive")
		(11 "B.Adhes" user "B.Adhesive")
		(13 "F.Paste" user "Package Geometry/Pastemask Top")
		(15 "B.Paste" user "Package Geometry/Pastemask Bottom")
		(5 "F.SilkS" user "Ref Des/Silkscreen Top")
		(7 "B.SilkS" user "Ref Des/Silkscreen Bottom")
		(1 "F.Mask" user "Board Geometry/Soldermask Top")
		(3 "B.Mask" user "Board Geometry/Soldermask Bottom")
		(17 "Dwgs.User" user "User.Drawings")
		(19 "Cmts.User" user "User.Comments")
		(21 "Eco1.User" user "User.Eco1")
		(23 "Eco2.User" user "User.Eco2")
		(25 "Edge.Cuts" user "Board Geometry/Outline")
		(27 "Margin" user)
		(31 "F.CrtYd" user "Package Geometry/Place Bound Top")
		(29 "B.CrtYd" user "Package Geometry/Place Bound Bottom")
		(35 "F.Fab" user "Ref Des/Assembly Top")
		(33 "B.Fab" user "Ref Des/Assembly Bottom")
	)
	(footprint ""
		(layer "B.Cu")
		(at 183.995568 -407.863802 -90)
		(property "Reference" "PR3927"
			(at 0 0 90)
			(layer "B.SilkS")
			(hide yes)
			(effects
				(font
					(size 1.27 1.27)
				)
				(justify mirror)
			)
		)
		(property "Value" ""
			(at 0 0 90)
			(layer "B.Fab")
			(effects
				(font
					(size 1.27 1.27)
				)
				(justify mirror)
			)
		)
		(duplicate_pad_numbers_are_jumpers no)
		(fp_line
			(start -0.7874 0.4064)
			(end 0.7874 0.4064)
			(stroke
				(width 0.1524)
				(type default)
			)
			(layer "B.SilkS")
		)
		(fp_line
			(start 0.7874 0.4064)
			(end 0.7874 -0.4064)
			(stroke
				(width 0.1524)
				(type default)
			)
			(layer "B.SilkS")
		)
		(fp_line
			(start -0.7874 -0.4064)
			(end -0.7874 0.4064)
			(stroke
				(width 0.1524)
				(type default)
			)
			(layer "B.SilkS")
		)
		(fp_line
			(start 0.7874 -0.4064)
			(end -0.7874 -0.4064)
			(stroke
				(width 0.1524)
				(type default)
			)
			(layer "B.SilkS")
		)
		(fp_line
			(start -0.67945 0.3048)
			(end -0.120396 0.3048)
			(stroke
				(width 0.1)
				(type default)
			)
			(layer "B.Fab")
		)
		(fp_line
			(start -0.120396 0.3048)
			(end -0.120396 0.2794)
			(stroke
				(width 0.1)
				(type default)
			)
			(layer "B.Fab")
		)
		(fp_line
			(start 0.12065 0.3048)
			(end 0.67945 0.3048)
			(stroke
				(width 0.1)
				(type default)
			)
			(layer "B.Fab")
		)
		(fp_line
			(start 0.67945 0.3048)
			(end 0.67945 -0.305054)
			(stroke
				(width 0.1)
				(type default)
			)
			(layer "B.Fab")
		)
		(fp_line
			(start -0.120396 0.2794)
			(end 0.12065 0.2794)
			(stroke
				(width 0.1)
				(type default)
			)
			(layer "B.Fab")
		)
		(fp_line
			(start 0.12065 0.2794)
			(end 0.12065 0.3048)
			(stroke
				(width 0.1)
				(type default)
			)
			(layer "B.Fab")
		)
		(fp_line
			(start -0.12065 -0.2794)
			(end -0.12065 -0.3048)
			(stroke
				(width 0.1)
				(type default)
			)
			(layer "B.Fab")
		)
		(fp_line
			(start 0.12065 -0.2794)
			(end -0.12065 -0.2794)
			(stroke
				(width 0.1)
				(type default)
			)
			(layer "B.Fab")
		)
		(fp_line
			(start -0.67945 -0.3048)
			(end -0.67945 0.3048)
			(stroke
				(width 0.1)
				(type default)
			)
			(layer "B.Fab")
		)
		(fp_line
			(start -0.12065 -0.3048)
			(end -0.67945 -0.3048)
			(stroke
				(width 0.1)
				(type default)
			)
			(layer "B.Fab")
		)
		(fp_line
			(start 0.12065 -0.305054)
			(end 0.12065 -0.2794)
			(stroke
				(width 0.1)
				(type default)
			)
			(layer "B.Fab")
		)
		(fp_line
			(start 0.67945 -0.305054)
			(end 0.12065 -0.305054)
			(stroke
				(width 0.1)
				(type default)
			)
			(layer "B.Fab")
		)
		(pad "1" smd circle
			(at 0.40005 0 90)
			(size 0 0)
			(layers "B.Cu" "B.Mask" "B.Paste")
			(net "HSC_VSENSE")
		)
		(pad "2" smd circle
			(at -0.40005 0 90)
			(size 0 0)
			(layers "B.Cu" "B.Mask" "B.Paste")
			(net "AGND_HSC")
		)
	)
	(footprint ""
		(layer "B.Cu")
		(at 409.30957 -149.65299 180)
		(property "Reference" "PC186"
			(at 0 0 0)
			(layer "B.SilkS")
			(hide yes)
			(effects
				(font
					(size 1.27 1.27)
				)
				(justify mirror)
			)
		)
		(property "Value" ""
			(at 0 0 0)
			(layer "B.Fab")
			(effects
				(font
					(size 1.27 1.27)
				)
				(justify mirror)
			)
		)
		(duplicate_pad_numbers_are_jumpers no)
		(fp_line
			(start 1.524 0.762)
			(end 1.524 -0.762)
			(stroke
				(width 0.1524)
				(type default)
			)
			(layer "B.SilkS")
		)
		(fp_line
			(start 1.524 -0.762)
			(end -1.524 -0.762)
			(stroke
				(width 0.1524)
				(type default)
			)
			(layer "B.SilkS")
		)
		(fp_line
			(start -1.524 0.762)
			(end 1.524 0.762)
			(stroke
				(width 0.1524)
				(type default)
			)
			(layer "B.SilkS")
		)
		(fp_line
			(start -1.524 -0.762)
			(end -1.524 0.762)
			(stroke
				(width 0.1524)
				(type default)
			)
			(layer "B.SilkS")
		)
		(fp_line
			(start 1.1049 0.724916)
			(end -1.1049 0.724916)
			(stroke
				(width 0.1)
				(type default)
			)
			(layer "B.Fab")
		)
		(fp_line
			(start 1.1049 -0.724916)
			(end 1.1049 0.724916)
			(stroke
				(width 0.1)
				(type default)
			)
			(layer "B.Fab")
		)
		(fp_line
			(start -1.1049 0.724916)
			(end -1.1049 -0.724916)
			(stroke
				(width 0.1)
				(type default)
			)
			(layer "B.Fab")
		)
		(fp_line
			(start -1.1049 -0.724916)
			(end 1.1049 -0.724916)
			(stroke
				(width 0.1)
				(type default)
			)
			(layer "B.Fab")
		)
		(pad "1" smd rect
			(at 0.889 0 180)
			(size 1.016 1.27)
			(layers "B.Cu" "B.Mask" "B.Paste")
			(net "PVCCFA_EHV_CPU0")
		)
		(pad "2" smd rect
			(at -0.889 0 180)
			(size 1.016 1.27)
			(layers "B.Cu" "B.Mask" "B.Paste")
			(net "GND")
		)
	)
	(footprint ""
		(layer "B.Cu")
		(at 96.241108 -190.705232 -90)
		(property "Reference" "R3024"
			(at 0 0 90)
			(layer "B.SilkS")
			(hide yes)
			(effects
				(font
					(size 1.27 1.27)
				)
				(justify mirror)
			)
		)
		(property "Value" ""
			(at 0 0 90)
			(layer "B.Fab")
			(effects
				(font
					(size 1.27 1.27)
				)
				(justify mirror)
			)
		)
		(duplicate_pad_numbers_are_jumpers no)
		(fp_line
			(start -0.7874 0.4064)
			(end 0.7874 0.4064)
			(stroke
				(width 0.1524)
				(type default)
			)
			(layer "B.SilkS")
		)
		(fp_line
			(start 0.7874 0.4064)
			(end 0.7874 -0.4064)
			(stroke
				(width 0.1524)
				(type default)
			)
			(layer "B.SilkS")
		)
		(fp_line
			(start -0.7874 -0.4064)
			(end -0.7874 0.4064)
			(stroke
				(width 0.1524)
				(type default)
			)
			(layer "B.SilkS")
		)
		(fp_line
			(start 0.7874 -0.4064)
			(end -0.7874 -0.4064)
			(stroke
				(width 0.1524)
				(type default)
			)
			(layer "B.SilkS")
		)
		(fp_line
			(start -0.67945 0.3048)
			(end -0.120396 0.3048)
			(stroke
				(width 0.1)
				(type default)
			)
			(layer "B.Fab")
		)
		(fp_line
			(start -0.120396 0.3048)
			(end -0.120396 0.2794)
			(stroke
				(width 0.1)
				(type default)
			)
			(layer "B.Fab")
		)
		(fp_line
			(start 0.12065 0.3048)
			(end 0.67945 0.3048)
			(stroke
				(width 0.1)
				(type default)
			)
			(layer "B.Fab")
		)
		(fp_line
			(start 0.67945 0.3048)
			(end 0.67945 -0.305054)
			(stroke
				(width 0.1)
				(type default)
			)
			(layer "B.Fab")
		)
		(fp_line
			(start -0.120396 0.2794)
			(end 0.12065 0.2794)
			(stroke
				(width 0.1)
				(type default)
			)
			(layer "B.Fab")
		)
		(fp_line
			(start 0.12065 0.2794)
			(end 0.12065 0.3048)
			(stroke
				(width 0.1)
				(type default)
			)
			(layer "B.Fab")
		)
		(fp_line
			(start -0.12065 -0.2794)
			(end -0.12065 -0.3048)
			(stroke
				(width 0.1)
				(type default)
			)
			(layer "B.Fab")
		)
		(fp_line
			(start 0.12065 -0.2794)
			(end -0.12065 -0.2794)
			(stroke
				(width 0.1)
				(type default)
			)
			(layer "B.Fab")
		)
		(fp_line
			(start -0.67945 -0.3048)
			(end -0.67945 0.3048)
			(stroke
				(width 0.1)
				(type default)
			)
			(layer "B.Fab")
		)
		(fp_line
			(start -0.12065 -0.3048)
			(end -0.67945 -0.3048)
			(stroke
				(width 0.1)
				(type default)
			)
			(layer "B.Fab")
		)
		(fp_line
			(start 0.12065 -0.305054)
			(end 0.12065 -0.2794)
			(stroke
				(width 0.1)
				(type default)
			)
			(layer "B.Fab")
		)
		(fp_line
			(start 0.67945 -0.305054)
			(end 0.12065 -0.305054)
			(stroke
				(width 0.1)
				(type default)
			)
			(layer "B.Fab")
		)
		(pad "1" smd circle
			(at 0.40005 0 90)
			(size 0 0)
			(layers "B.Cu" "B.Mask" "B.Paste")
			(net "GND")
		)
		(pad "2" smd circle
			(at -0.40005 0 90)
			(size 0 0)
			(layers "B.Cu" "B.Mask" "B.Paste")
			(net "PD_EXT_CLK_SEL_CPU1")
		)
	)
	(footprint ""
		(layer "B.Cu")
		(at 61.690758 -179.02555)
		(property "Reference" "PR4250"
			(at 0 0 0)
			(layer "B.SilkS")
			(hide yes)
			(effects
				(font
					(size 1.27 1.27)
				)
				(justify mirror)
			)
		)
		(property "Value" ""
			(at 0 0 0)
			(layer "B.Fab")
			(effects
				(font
					(size 1.27 1.27)
				)
				(justify mirror)
			)
		)
		(duplicate_pad_numbers_are_jumpers no)
		(fp_line
			(start -0.7874 -0.4064)
			(end -0.7874 0.4064)
			(stroke
				(width 0.1524)
				(type default)
			)
			(layer "B.SilkS")
		)
		(fp_line
			(start -0.7874 0.4064)
			(end 0.7874 0.4064)
			(stroke
				(width 0.1524)
				(type default)
			)
			(layer "B.SilkS")
		)
		(fp_line
			(start 0.7874 -0.4064)
			(end -0.7874 -0.4064)
			(stroke
				(width 0.1524)
				(type default)
			)
			(layer "B.SilkS")
		)
		(fp_line
			(start 0.7874 0.4064)
			(end 0.7874 -0.4064)
			(stroke
				(width 0.1524)
				(type default)
			)
			(layer "B.SilkS")
		)
		(fp_line
			(start -0.67945 -0.3048)
			(end -0.67945 0.3048)
			(stroke
				(width 0.1)
				(type default)
			)
			(layer "B.Fab")
		)
		(fp_line
			(start -0.67945 0.3048)
			(end -0.120396 0.3048)
			(stroke
				(width 0.1)
				(type default)
			)
			(layer "B.Fab")
		)
		(fp_line
			(start -0.12065 -0.3048)
			(end -0.67945 -0.3048)
			(stroke
				(width 0.1)
				(type default)
			)
			(layer "B.Fab")
		)
		(fp_line
			(start -0.12065 -0.2794)
			(end -0.12065 -0.3048)
			(stroke
				(width 0.1)
				(type default)
			)
			(layer "B.Fab")
		)
		(fp_line
			(start -0.120396 0.2794)
			(end 0.12065 0.2794)
			(stroke
				(width 0.1)
				(type default)
			)
			(layer "B.Fab")
		)
		(fp_line
			(start -0.120396 0.3048)
			(end -0.120396 0.2794)
			(stroke
				(width 0.1)
				(type default)
			)
			(layer "B.Fab")
		)
		(fp_line
			(start 0.12065 -0.305054)
			(end 0.12065 -0.2794)
			(stroke
				(width 0.1)
				(type default)
			)
			(layer "B.Fab")
		)
		(fp_line
			(start 0.12065 -0.2794)
			(end -0.12065 -0.2794)
			(stroke
				(width 0.1)
				(type default)
			)
			(layer "B.Fab")
		)
		(fp_line
			(start 0.12065 0.2794)
			(end 0.12065 0.3048)
			(stroke
				(width 0.1)
				(type default)
			)
			(layer "B.Fab")
		)
		(fp_line
			(start 0.12065 0.3048)
			(end 0.67945 0.3048)
			(stroke
				(width 0.1)
				(type default)
			)
			(layer "B.Fab")
		)
		(fp_line
			(start 0.67945 -0.305054)
			(end 0.12065 -0.305054)
			(stroke
				(width 0.1)
				(type default)
			)
			(layer "B.Fab")
		)
		(fp_line
			(start 0.67945 0.3048)
			(end 0.67945 -0.305054)
			(stroke
				(width 0.1)
				(type default)
			)
			(layer "B.Fab")
		)
		(pad "1" smd circle
			(at 0.40005 0 180)
			(size 0 0)
			(layers "B.Cu" "B.Mask" "B.Paste")
			(net "PVCCFA_EHV_CPU1")
		)
		(pad "2" smd circle
			(at -0.40005 0 180)
			(size 0 0)
			(layers "B.Cu" "B.Mask" "B.Paste")
			(net "GND")
		)
	)
	(footprint ""
		(layer "B.Cu")
		(at 317.90259 -30.507178 180)
		(property "Reference" "R3038"
			(at 0 0 0)
			(layer "B.SilkS")
			(hide yes)
			(effects
				(font
					(size 1.27 1.27)
				)
				(justify mirror)
			)
		)
		(property "Value" ""
			(at 0 0 0)
			(layer "B.Fab")
			(effects
				(font
					(size 1.27 1.27)
				)
				(justify mirror)
			)
		)
		(duplicate_pad_numbers_are_jumpers no)
		(fp_line
			(start 0.7874 0.4064)
			(end 0.7874 -0.4064)
			(stroke
				(width 0.1524)
				(type default)
			)
			(layer "B.SilkS")
		)
		(fp_line
			(start 0.7874 -0.4064)
			(end -0.7874 -0.4064)
			(stroke
				(width 0.1524)
				(type default)
			)
			(layer "B.SilkS")
		)
		(fp_line
			(start -0.7874 0.4064)
			(end 0.7874 0.4064)
			(stroke
				(width 0.1524)
				(type default)
			)
			(layer "B.SilkS")
		)
		(fp_line
			(start -0.7874 -0.4064)
			(end -0.7874 0.4064)
			(stroke
				(width 0.1524)
				(type default)
			)
			(layer "B.SilkS")
		)
		(fp_line
			(start 0.67945 0.3048)
			(end 0.67945 -0.305054)
			(stroke
				(width 0.1)
				(type default)
			)
			(layer "B.Fab")
		)
		(fp_line
			(start 0.67945 -0.305054)
			(end 0.12065 -0.305054)
			(stroke
				(width 0.1)
				(type default)
			)
			(layer "B.Fab")
		)
		(fp_line
			(start 0.12065 0.3048)
			(end 0.67945 0.3048)
			(stroke
				(width 0.1)
				(type default)
			)
			(layer "B.Fab")
		)
		(fp_line
			(start 0.12065 0.2794)
			(end 0.12065 0.3048)
			(stroke
				(width 0.1)
				(type default)
			)
			(layer "B.Fab")
		)
		(fp_line
			(start 0.12065 -0.2794)
			(end -0.12065 -0.2794)
			(stroke
				(width 0.1)
				(type default)
			)
			(layer "B.Fab")
		)
		(fp_line
			(start 0.12065 -0.305054)
			(end 0.12065 -0.2794)
			(stroke
				(width 0.1)
				(type default)
			)
			(layer "B.Fab")
		)
		(fp_line
			(start -0.120396 0.3048)
			(end -0.120396 0.2794)
			(stroke
				(width 0.1)
				(type default)
			)
			(layer "B.Fab")
		)
		(fp_line
			(start -0.120396 0.2794)
			(end 0.12065 0.2794)
			(stroke
				(width 0.1)
				(type default)
			)
			(layer "B.Fab")
		)
		(fp_line
			(start -0.12065 -0.2794)
			(end -0.12065 -0.3048)
			(stroke
				(width 0.1)
				(type default)
			)
			(layer "B.Fab")
		)
		(fp_line
			(start -0.12065 -0.3048)
			(end -0.67945 -0.3048)
			(stroke
				(width 0.1)
				(type default)
			)
			(layer "B.Fab")
		)
		(fp_line
			(start -0.67945 0.3048)
			(end -0.120396 0.3048)
			(stroke
				(width 0.1)
				(type default)
			)
			(layer "B.Fab")
		)
		(fp_line
			(start -0.67945 -0.3048)
			(end -0.67945 0.3048)
			(stroke
				(width 0.1)
				(type default)
			)
			(layer "B.Fab")
		)
		(pad "1" smd circle
			(at 0.40005 0)
			(size 0 0)
			(layers "B.Cu" "B.Mask" "B.Paste")
			(net "P3V3_AUX")
		)
		(pad "2" smd circle
			(at -0.40005 0)
			(size 0 0)
			(layers "B.Cu" "B.Mask" "B.Paste")
			(net "FM_PCH_SPARE0")
		)
	)
	(footprint ""
		(layer "B.Cu")
		(at 176.555654 -115.775486 90)
		(property "Reference" "C1933"
			(at 0 0 90)
			(layer "B.SilkS")
			(hide yes)
			(effects
				(font
					(size 1.27 1.27)
				)
				(justify mirror)
			)
		)
		(property "Value" ""
			(at 0 0 90)
			(layer "B.Fab")
			(effects
				(font
					(size 1.27 1.27)
				)
				(justify mirror)
			)
		)
		(duplicate_pad_numbers_are_jumpers no)
		(fp_line
			(start 0.69215 -0.2921)
			(end -0.69215 -0.2921)
			(stroke
				(width 0.1524)
				(type default)
			)
			(layer "B.SilkS")
		)
		(fp_line
			(start -0.69215 -0.2921)
			(end -0.69215 0.2921)
			(stroke
				(width 0.1524)
				(type default)
			)
			(layer "B.SilkS")
		)
		(fp_line
			(start 0.69215 0.2921)
			(end 0.69215 -0.2921)
			(stroke
				(width 0.1524)
				(type default)
			)
			(layer "B.SilkS")
		)
		(fp_line
			(start -0.69215 0.2921)
			(end 0.69215 0.2921)
			(stroke
				(width 0.1524)
				(type default)
			)
			(layer "B.SilkS")
		)
		(fp_line
			(start 0.51435 -0.2794)
			(end -0.51435 -0.2794)
			(stroke
				(width 0.1)
				(type default)
			)
			(layer "B.Fab")
		)
		(fp_line
			(start -0.51435 -0.2794)
			(end -0.51435 0.2794)
			(stroke
				(width 0.1)
				(type default)
			)
			(layer "B.Fab")
		)
		(fp_line
			(start 0.51435 0.2794)
			(end 0.51435 -0.2794)
			(stroke
				(width 0.1)
				(type default)
			)
			(layer "B.Fab")
		)
		(fp_line
			(start -0.51435 0.2794)
			(end 0.51435 0.2794)
			(stroke
				(width 0.1)
				(type default)
			)
			(layer "B.Fab")
		)
		(pad "1" smd circle
			(at 0.40005 0 270)
			(size 0 0)
			(layers "B.Cu" "B.Mask" "B.Paste")
			(net "P3V3_AUX_FPGA_VCCIO1")
		)
		(pad "2" smd circle
			(at -0.40005 0 270)
			(size 0 0)
			(layers "B.Cu" "B.Mask" "B.Paste")
			(net "GND")
		)
		(zone
			(layer "B.Cu")
			(hatch none 0.5)
			(connect_pads
				(clearance 0)
			)
			(min_thickness 0.25)
			(keepout
				(tracks not_allowed)
				(vias allowed)
				(pads allowed)
				(copperpour not_allowed)
				(footprints allowed)
			)
			(placement
				(enabled no)
				(sheetname "")
			)
			(fill
				(thermal_gap 0.5)
				(thermal_bridge_width 0.5)
				(island_removal_mode 0)
			)
			(polygon
				(pts
					(xy 176.643284 -115.965986) (xy 176.70145 -115.874546) (xy 176.70145 -115.675156) (xy 176.643284 -115.584986)
					(xy 176.468024 -115.584986) (xy 176.409604 -115.675156) (xy 176.409604 -115.874546) (xy 176.46777 -115.965986)
				)
			)
		)
	)
	(footprint ""
		(layer "B.Cu")
		(at 193.38036 -118.074948 180)
		(property "Reference" "R1419"
			(at 0 0 0)
			(layer "B.SilkS")
			(hide yes)
			(effects
				(font
					(size 1.27 1.27)
				)
				(justify mirror)
			)
		)
		(property "Value" ""
			(at 0 0 0)
			(layer "B.Fab")
			(effects
				(font
					(size 1.27 1.27)
				)
				(justify mirror)
			)
		)
		(duplicate_pad_numbers_are_jumpers no)
		(fp_line
			(start 0.7874 0.4064)
			(end 0.7874 -0.4064)
			(stroke
				(width 0.1524)
				(type default)
			)
			(layer "B.SilkS")
		)
		(fp_line
			(start 0.7874 -0.4064)
			(end -0.7874 -0.4064)
			(stroke
				(width 0.1524)
				(type default)
			)
			(layer "B.SilkS")
		)
		(fp_line
			(start -0.7874 0.4064)
			(end 0.7874 0.4064)
			(stroke
				(width 0.1524)
				(type default)
			)
			(layer "B.SilkS")
		)
		(fp_line
			(start -0.7874 -0.4064)
			(end -0.7874 0.4064)
			(stroke
				(width 0.1524)
				(type default)
			)
			(layer "B.SilkS")
		)
		(fp_line
			(start 0.67945 0.3048)
			(end 0.67945 -0.305054)
			(stroke
				(width 0.1)
				(type default)
			)
			(layer "B.Fab")
		)
		(fp_line
			(start 0.67945 -0.305054)
			(end 0.12065 -0.305054)
			(stroke
				(width 0.1)
				(type default)
			)
			(layer "B.Fab")
		)
		(fp_line
			(start 0.12065 0.3048)
			(end 0.67945 0.3048)
			(stroke
				(width 0.1)
				(type default)
			)
			(layer "B.Fab")
		)
		(fp_line
			(start 0.12065 0.2794)
			(end 0.12065 0.3048)
			(stroke
				(width 0.1)
				(type default)
			)
			(layer "B.Fab")
		)
		(fp_line
			(start 0.12065 -0.2794)
			(end -0.12065 -0.2794)
			(stroke
				(width 0.1)
				(type default)
			)
			(layer "B.Fab")
		)
		(fp_line
			(start 0.12065 -0.305054)
			(end 0.12065 -0.2794)
			(stroke
				(width 0.1)
				(type default)
			)
			(layer "B.Fab")
		)
		(fp_line
			(start -0.120396 0.3048)
			(end -0.120396 0.2794)
			(stroke
				(width 0.1)
				(type default)
			)
			(layer "B.Fab")
		)
		(fp_line
			(start -0.120396 0.2794)
			(end 0.12065 0.2794)
			(stroke
				(width 0.1)
				(type default)
			)
			(layer "B.Fab")
		)
		(fp_line
			(start -0.12065 -0.2794)
			(end -0.12065 -0.3048)
			(stroke
				(width 0.1)
				(type default)
			)
			(layer "B.Fab")
		)
		(fp_line
			(start -0.12065 -0.3048)
			(end -0.67945 -0.3048)
			(stroke
				(width 0.1)
				(type default)
			)
			(layer "B.Fab")
		)
		(fp_line
			(start -0.67945 0.3048)
			(end -0.120396 0.3048)
			(stroke
				(width 0.1)
				(type default)
			)
			(layer "B.Fab")
		)
		(fp_line
			(start -0.67945 -0.3048)
			(end -0.67945 0.3048)
			(stroke
				(width 0.1)
				(type default)
			)
			(layer "B.Fab")
		)
		(pad "1" smd circle
			(at 0.40005 0)
			(size 0 0)
			(layers "B.Cu" "B.Mask" "B.Paste")
			(net "RST_PCIE_PCH_DEV_PERST_N")
		)
		(pad "2" smd circle
			(at -0.40005 0)
			(size 0 0)
			(layers "B.Cu" "B.Mask" "B.Paste")
			(net "GND")
		)
	)
)
